# S9S_MB_2U (Grand Teton) — schematic netlist excerpt (pin names and nets, part order shuffled) for the footprints in the layout excerpt that follows; sources: Cadence DE-HDL packaged netlist, KiCad conversion of 03242023_DA0F0TMBIJ0_F0T_Motherboard_J_brd_V01_OCP.brd

R4517  Q_RES  10K 1% CHIP  pkg 0402LF  page 206 : A = P3V3 ; B = OCP_SFF_CLK_OE_N
R3832  Q_RES  0 5% CHIP  pkg 0402LF  page 162 : A = P3V3_OCP_PWRGD_2 ; B = OCP_V3_2_P3V3_PWRGD

(kicad_pcb
	(version 20260206)
	(generator "pcbnew")
	(generator_version "10.0")
	(general
		(thickness 1.6)
		(legacy_teardrops no)
	)
	(paper "A4")
	(title_block
		(title "03242023_DA0F0TMBIJ0_F0T_Motherboard_J_brd_V01_OCP.brd")
		(comment 1 "Grand Teton / footprints 5206-5207 of 6105")
	)
	(layers
		(0 "F.Cu" signal "TOP")
		(4 "In1.Cu" signal "GND")
		(6 "In2.Cu" signal "IN1")
		(8 "In3.Cu" signal "GND1")
		(10 "In4.Cu" signal "IN2")
		(12 "In5.Cu" signal "GND2")
		(14 "In6.Cu" signal "IN3")
		(16 "In7.Cu" signal "GND3")
		(18 "In8.Cu" signal "VCC")
		(20 "In9.Cu" signal "VCC1")
		(22 "In10.Cu" signal "GND4")
		(24 "In11.Cu" signal "IN4")
		(26 "In12.Cu" signal "GND5")
		(28 "In13.Cu" signal "IN5")
		(30 "In14.Cu" signal "GND6")
		(32 "In15.Cu" signal "IN6")
		(34 "In16.Cu" signal "GND7")
		(2 "B.Cu" signal "BOTTOM")
		(9 "F.Adhes" user "F.Adhesive")
		(11 "B.Adhes" user "B.Adhesive")
		(13 "F.Paste" user "Package Geometry/Pastemask Top")
		(15 "B.Paste" user "Package Geometry/Pastemask Bottom")
		(5 "F.SilkS" user "Ref Des/Silkscreen Top")
		(7 "B.SilkS" user "Ref Des/Silkscreen Bottom")
		(1 "F.Mask" user "Board Geometry/Soldermask Top")
		(3 "B.Mask" user "Board Geometry/Soldermask Bottom")
		(17 "Dwgs.User" user "User.Drawings")
		(19 "Cmts.User" user "User.Comments")
		(21 "Eco1.User" user "User.Eco1")
		(23 "Eco2.User" user "User.Eco2")
		(25 "Edge.Cuts" user "Board Geometry/Outline")
		(27 "Margin" user)
		(31 "F.CrtYd" user "Package Geometry/Place Bound Top")
		(29 "B.CrtYd" user "Package Geometry/Place Bound Bottom")
		(35 "F.Fab" user "Ref Des/Assembly Top")
		(33 "B.Fab" user "Ref Des/Assembly Bottom")
	)
	(footprint ""
		(layer "B.Cu")
		(at 228.114098 -117.960648 -90)
		(property "Reference" "R4517"
			(at 0 0 90)
			(layer "B.SilkS")
			(hide yes)
			(effects
				(font
					(size 1.27 1.27)
				)
				(justify mirror)
			)
		)
		(property "Value" ""
			(at 0 0 90)
			(layer "B.Fab")
			(effects
				(font
					(size 1.27 1.27)
				)
				(justify mirror)
			)
		)
		(duplicate_pad_numbers_are_jumpers no)
		(fp_line
			(start -0.7874 0.4064)
			(end 0.7874 0.4064)
			(stroke
				(width 0.1524)
				(type default)
			)
			(layer "B.SilkS")
		)
		(fp_line
			(start 0.7874 0.4064)
			(end 0.7874 -0.4064)
			(stroke
				(width 0.1524)
				(type default)
			)
			(layer "B.SilkS")
		)
		(fp_line
			(start -0.7874 -0.4064)
			(end -0.7874 0.4064)
			(stroke
				(width 0.1524)
				(type default)
			)
			(layer "B.SilkS")
		)
		(fp_line
			(start 0.7874 -0.4064)
			(end -0.7874 -0.4064)
			(stroke
				(width 0.1524)
				(type default)
			)
			(layer "B.SilkS")
		)
		(fp_line
			(start -0.67945 0.3048)
			(end -0.120396 0.3048)
			(stroke
				(width 0.1)
				(type default)
			)
			(layer "B.Fab")
		)
		(fp_line
			(start -0.120396 0.3048)
			(end -0.120396 0.2794)
			(stroke
				(width 0.1)
				(type default)
			)
			(layer "B.Fab")
		)
		(fp_line
			(start 0.12065 0.3048)
			(end 0.67945 0.3048)
			(stroke
				(width 0.1)
				(type default)
			)
			(layer "B.Fab")
		)
		(fp_line
			(start 0.67945 0.3048)
			(end 0.67945 -0.305054)
			(stroke
				(width 0.1)
				(type default)
			)
			(layer "B.Fab")
		)
		(fp_line
			(start -0.120396 0.2794)
			(end 0.12065 0.2794)
			(stroke
				(width 0.1)
				(type default)
			)
			(layer "B.Fab")
		)
		(fp_line
			(start 0.12065 0.2794)
			(end 0.12065 0.3048)
			(stroke
				(width 0.1)
				(type default)
			)
			(layer "B.Fab")
		)
		(fp_line
			(start -0.12065 -0.2794)
			(end -0.12065 -0.3048)
			(stroke
				(width 0.1)
				(type default)
			)
			(layer "B.Fab")
		)
		(fp_line
			(start 0.12065 -0.2794)
			(end -0.12065 -0.2794)
			(stroke
				(width 0.1)
				(type default)
			)
			(layer "B.Fab")
		)
		(fp_line
			(start -0.67945 -0.3048)
			(end -0.67945 0.3048)
			(stroke
				(width 0.1)
				(type default)
			)
			(layer "B.Fab")
		)
		(fp_line
			(start -0.12065 -0.3048)
			(end -0.67945 -0.3048)
			(stroke
				(width 0.1)
				(type default)
			)
			(layer "B.Fab")
		)
		(fp_line
			(start 0.12065 -0.305054)
			(end 0.12065 -0.2794)
			(stroke
				(width 0.1)
				(type default)
			)
			(layer "B.Fab")
		)
		(fp_line
			(start 0.67945 -0.305054)
			(end 0.12065 -0.305054)
			(stroke
				(width 0.1)
				(type default)
			)
			(layer "B.Fab")
		)
		(pad "1" smd circle
			(at 0.40005 0 90)
			(size 0 0)
			(layers "B.Cu" "B.Mask" "B.Paste")
			(net "P3V3")
		)
		(pad "2" smd circle
			(at -0.40005 0 90)
			(size 0 0)
			(layers "B.Cu" "B.Mask" "B.Paste")
			(net "OCP_SFF_CLK_OE_N")
		)
	)
	(footprint ""
		(layer "B.Cu")
		(at 80.35163 -52.482496 90)
		(property "Reference" "R3832"
			(at 0 0 90)
			(layer "B.SilkS")
			(hide yes)
			(effects
				(font
					(size 1.27 1.27)
				)
				(justify mirror)
			)
		)
		(property "Value" ""
			(at 0 0 90)
			(layer "B.Fab")
			(effects
				(font
					(size 1.27 1.27)
				)
				(justify mirror)
			)
		)
		(duplicate_pad_numbers_are_jumpers no)
		(fp_line
			(start 0.7874 -0.4064)
			(end -0.7874 -0.4064)
			(stroke
				(width 0.1524)
				(type default)
			)
			(layer "B.SilkS")
		)
		(fp_line
			(start -0.7874 -0.4064)
			(end -0.7874 0.4064)
			(stroke
				(width 0.1524)
				(type default)
			)
			(layer "B.SilkS")
		)
		(fp_line
			(start 0.7874 0.4064)
			(end 0.7874 -0.4064)
			(stroke
				(width 0.1524)
				(type default)
			)
			(layer "B.SilkS")
		)
		(fp_line
			(start -0.7874 0.4064)
			(end 0.7874 0.4064)
			(stroke
				(width 0.1524)
				(type default)
			)
			(layer "B.SilkS")
		)
		(fp_line
			(start 0.67945 -0.305054)
			(end 0.12065 -0.305054)
			(stroke
				(width 0.1)
				(type default)
			)
			(layer "B.Fab")
		)
		(fp_line
			(start 0.12065 -0.305054)
			(end 0.12065 -0.2794)
			(stroke
				(width 0.1)
				(type default)
			)
			(layer "B.Fab")
		)
		(fp_line
			(start -0.12065 -0.3048)
			(end -0.67945 -0.3048)
			(stroke
				(width 0.1)
				(type default)
			)
			(layer "B.Fab")
		)
		(fp_line
			(start -0.67945 -0.3048)
			(end -0.67945 0.3048)
			(stroke
				(width 0.1)
				(type default)
			)
			(layer "B.Fab")
		)
		(fp_line
			(start 0.12065 -0.2794)
			(end -0.12065 -0.2794)
			(stroke
				(width 0.1)
				(type default)
			)
			(layer "B.Fab")
		)
		(fp_line
			(start -0.12065 -0.2794)
			(end -0.12065 -0.3048)
			(stroke
				(width 0.1)
				(type default)
			)
			(layer "B.Fab")
		)
		(fp_line
			(start 0.12065 0.2794)
			(end 0.12065 0.3048)
			(stroke
				(width 0.1)
				(type default)
			)
			(layer "B.Fab")
		)
		(fp_line
			(start -0.120396 0.2794)
			(end 0.12065 0.2794)
			(stroke
				(width 0.1)
				(type default)
			)
			(layer "B.Fab")
		)
		(fp_line
			(start 0.67945 0.3048)
			(end 0.67945 -0.305054)
			(stroke
				(width 0.1)
				(type default)
			)
			(layer "B.Fab")
		)
		(fp_line
			(start 0.12065 0.3048)
			(end 0.67945 0.3048)
			(stroke
				(width 0.1)
				(type default)
			)
			(layer "B.Fab")
		)
		(fp_line
			(start -0.120396 0.3048)
			(end -0.120396 0.2794)
			(stroke
				(width 0.1)
				(type default)
			)
			(layer "B.Fab")
		)
		(fp_line
			(start -0.67945 0.3048)
			(end -0.120396 0.3048)
			(stroke
				(width 0.1)
				(type default)
			)
			(layer "B.Fab")
		)
		(pad "1" smd circle
			(at 0.40005 0 270)
			(size 0 0)
			(layers "B.Cu" "B.Mask" "B.Paste")
			(net "P3V3_OCP_PWRGD_2")
		)
		(pad "2" smd circle
			(at -0.40005 0 270)
			(size 0 0)
			(layers "B.Cu" "B.Mask" "B.Paste")
			(net "OCP_V3_2_P3V3_PWRGD")
		)
	)
)
